(kicad_pcb
	(version 20260206)
	(generator "pcbnew")
	(generator_version "10.0")
	(general
		(thickness 1.6)
		(legacy_teardrops no)
	)
	(paper "A4")
	(title_block
		(title "Bryce Canyon_SCC_16316-1_OCP.brd")
		(comment 1 "Bryce Canyon / footprints 944-952 of 1561")
	)
	(layers
		(0 "F.Cu" signal "TOP")
		(4 "In1.Cu" signal "L2GND")
		(6 "In2.Cu" signal "L3")
		(8 "In3.Cu" signal "L4VCC")
		(10 "In4.Cu" signal "L5VCC")
		(12 "In5.Cu" signal "L6")
		(14 "In6.Cu" signal "L7GND")
		(2 "B.Cu" signal "BOTTOM")
		(9 "F.Adhes" user "F.Adhesive")
		(11 "B.Adhes" user "B.Adhesive")
		(13 "F.Paste" user "Package Geometry/Pastemask Top")
		(15 "B.Paste" user "Package Geometry/Pastemask Bottom")
		(5 "F.SilkS" user "Ref Des/Silkscreen Top")
		(7 "B.SilkS" user "Ref Des/Silkscreen Bottom")
		(1 "F.Mask" user "Board Geometry/Soldermask Top")
		(3 "B.Mask" user "Board Geometry/Soldermask Bottom")
		(17 "Dwgs.User" user "User.Drawings")
		(19 "Cmts.User" user "User.Comments")
		(21 "Eco1.User" user "User.Eco1")
		(23 "Eco2.User" user "User.Eco2")
		(25 "Edge.Cuts" user "Board Geometry/Outline")
		(27 "Margin" user)
		(31 "F.CrtYd" user "Package Geometry/Place Bound Top")
		(29 "B.CrtYd" user "Package Geometry/Place Bound Bottom")
		(35 "F.Fab" user "Ref Des/Assembly Top")
		(33 "B.Fab" user "Ref Des/Assembly Bottom")
	)
	(footprint ""
		(layer "B.Cu")
		(at 186.963812 -46.168056 -90)
		(property "Reference" "TP110"
			(at 0 0 90)
			(layer "B.SilkS")
			(hide yes)
			(effects
				(font
					(size 1.27 1.27)
				)
				(justify mirror)
			)
		)
		(property "Value" "TPAD28-2-GP"
			(at 0.0127 -1.6637 270)
			(unlocked yes)
			(layer "B.Fab")
			(hide yes)
			(effects
				(font
					(size 1.016 1.016)
					(thickness 0.1524)
				)
				(justify mirror)
			)
		)
		(property "Device Type" "TPAD28"
			(at 0.0127 -3.1877 270)
			(unlocked yes)
			(layer "B.Fab")
			(hide yes)
			(effects
				(font
					(size 1.016 1.016)
					(thickness 0.1524)
				)
				(justify mirror)
			)
		)
		(duplicate_pad_numbers_are_jumpers no)
		(fp_poly
			(pts
				(arc
					(start 0 -0.3556)
					(mid 0 0.3556)
					(end 0 -0.3556)
				)
			)
			(stroke
				(width 0)
				(type default)
			)
			(fill no)
			(layer "B.CrtYd")
		)
		(fp_poly
			(pts
				(arc
					(start 0 -0.6096)
					(mid 0 0.6096)
					(end 0 -0.6096)
				)
			)
			(stroke
				(width 0)
				(type default)
			)
			(fill no)
			(layer "B.Fab")
		)
		(pad "1" smd circle
			(at 0 0 90)
			(size 0.7112 0.7112)
			(layers "B.Cu" "B.Mask" "B.Paste")
			(net "XM_ADDR_25")
		)
	)
	(footprint ""
		(layer "B.Cu")
		(at 185.4708 -24.9428 90)
		(property "Reference" "TP67"
			(at 0 0 90)
			(layer "B.SilkS")
			(hide yes)
			(effects
				(font
					(size 1.27 1.27)
				)
				(justify mirror)
			)
		)
		(property "Value" "TPAD28-2-GP"
			(at 0.0127 -1.6637 90)
			(unlocked yes)
			(layer "B.Fab")
			(hide yes)
			(effects
				(font
					(size 1.016 1.016)
					(thickness 0.1524)
				)
				(justify mirror)
			)
		)
		(property "Device Type" "TPAD28"
			(at 0.0127 -3.1877 90)
			(unlocked yes)
			(layer "B.Fab")
			(hide yes)
			(effects
				(font
					(size 1.016 1.016)
					(thickness 0.1524)
				)
				(justify mirror)
			)
		)
		(duplicate_pad_numbers_are_jumpers no)
		(fp_poly
			(pts
				(arc
					(start 0 0.3556)
					(mid 0 -0.3556)
					(end 0 0.3556)
				)
			)
			(stroke
				(width 0)
				(type default)
			)
			(fill no)
			(layer "B.CrtYd")
		)
		(fp_poly
			(pts
				(arc
					(start 0 0.6096)
					(mid 0 -0.6096)
					(end 0 0.6096)
				)
			)
			(stroke
				(width 0)
				(type default)
			)
			(fill no)
			(layer "B.Fab")
		)
		(pad "1" smd circle
			(at 0 0 270)
			(size 0.7112 0.7112)
			(layers "B.Cu" "B.Mask" "B.Paste")
			(net "IOC_GPIO_14")
		)
	)
	(footprint ""
		(layer "B.Cu")
		(at 118.999 -84.709)
		(property "Reference" "TP157"
			(at 0 0 0)
			(layer "B.SilkS")
			(hide yes)
			(effects
				(font
					(size 1.27 1.27)
				)
				(justify mirror)
			)
		)
		(property "Value" "TPAD28-2-GP"
			(at 0.0127 -1.6637 0)
			(unlocked yes)
			(layer "B.Fab")
			(hide yes)
			(effects
				(font
					(size 1.016 1.016)
					(thickness 0.1524)
				)
				(justify mirror)
			)
		)
		(property "Device Type" "TPAD28"
			(at 0.0127 -3.1877 0)
			(unlocked yes)
			(layer "B.Fab")
			(hide yes)
			(effects
				(font
					(size 1.016 1.016)
					(thickness 0.1524)
				)
				(justify mirror)
			)
		)
		(duplicate_pad_numbers_are_jumpers no)
		(fp_poly
			(pts
				(arc
					(start 0.3556 0)
					(mid -0.3556 0)
					(end 0.3556 0)
				)
			)
			(stroke
				(width 0)
				(type default)
			)
			(fill no)
			(layer "B.CrtYd")
		)
		(fp_poly
			(pts
				(arc
					(start 0.6096 0)
					(mid -0.6096 0)
					(end 0.6096 0)
				)
			)
			(stroke
				(width 0)
				(type default)
			)
			(fill no)
			(layer "B.Fab")
		)
		(pad "1" smd circle
			(at 0 0 180)
			(size 0.7112 0.7112)
			(layers "B.Cu" "B.Mask" "B.Paste")
			(net "ICE_TCK")
		)
	)
	(footprint ""
		(layer "B.Cu")
		(at 108.712 -72.009)
		(property "Reference" "C128"
			(at 0 0 0)
			(layer "B.SilkS")
			(hide yes)
			(effects
				(font
					(size 1.27 1.27)
				)
				(justify mirror)
			)
		)
		(property "Value" "SCD1U6D3V1KX-GP"
			(at 2.8321 -1.7399 0)
			(unlocked yes)
			(layer "B.Fab")
			(hide yes)
			(effects
				(font
					(size 1.016 1.016)
					(thickness 0.1524)
				)
				(justify mirror)
			)
		)
		(property "Device Type" "C0201H13"
			(at 2.8321 -3.2639 0)
			(unlocked yes)
			(layer "B.Fab")
			(hide yes)
			(effects
				(font
					(size 1.016 1.016)
					(thickness 0.1524)
				)
				(justify mirror)
			)
		)
		(duplicate_pad_numbers_are_jumpers no)
		(fp_rect
			(start 0.2794 0.6477)
			(end -0.2794 -0.6477)
			(stroke
				(width 0)
				(type default)
			)
			(fill no)
			(layer "B.CrtYd")
		)
		(fp_rect
			(start 0.2794 0.6477)
			(end -0.2794 -0.6477)
			(stroke
				(width 0)
				(type default)
			)
			(fill no)
			(layer "B.Fab")
		)
		(pad "1" smd custom
			(at 0 -0.2794 180)
			(size 0.0762 0.0762)
			(layers "B.Cu" "B.Mask" "B.Paste")
			(net "P1V8_E")
			(options
				(clearance outline)
				(anchor circle)
			)
			(primitives
				(gr_poly
					(pts
						(arc
							(start 0.1524 0.127)
							(mid 0.137521 0.162921)
							(end 0.1016 0.1778)
						)
						(arc
							(start -0.1016 0.1778)
							(mid -0.137521 0.162921)
							(end -0.1524 0.127)
						)
						(arc
							(start -0.1524 -0.127)
							(mid -0.137521 -0.162921)
							(end -0.1016 -0.1778)
						)
						(arc
							(start 0.1016 -0.1778)
							(mid 0.137521 -0.162921)
							(end 0.1524 -0.127)
						)
					)
					(width 0)
					(fill yes)
				)
			)
		)
		(pad "2" smd custom
			(at 0 0.2794 180)
			(size 0.0762 0.0762)
			(layers "B.Cu" "B.Mask" "B.Paste")
			(net "GND")
			(options
				(clearance outline)
				(anchor circle)
			)
			(primitives
				(gr_poly
					(pts
						(arc
							(start 0.1524 0.127)
							(mid 0.137521 0.162921)
							(end 0.1016 0.1778)
						)
						(arc
							(start -0.1016 0.1778)
							(mid -0.137521 0.162921)
							(end -0.1524 0.127)
						)
						(arc
							(start -0.1524 -0.127)
							(mid -0.137521 -0.162921)
							(end -0.1016 -0.1778)
						)
						(arc
							(start 0.1016 -0.1778)
							(mid 0.137521 -0.162921)
							(end 0.1524 -0.127)
						)
					)
					(width 0)
					(fill yes)
				)
			)
		)
	)
	(footprint ""
		(layer "B.Cu")
		(at 187.1472 -24.8666 -90)
		(property "Reference" "R234"
			(at 0 0 90)
			(layer "B.SilkS")
			(hide yes)
			(effects
				(font
					(size 1.27 1.27)
				)
				(justify mirror)
			)
		)
		(property "Value" "4K7R2F-GP"
			(at -0.064008 -3.993896 270)
			(unlocked yes)
			(layer "B.Fab")
			(hide yes)
			(effects
				(font
					(size 1.016 1.016)
					(thickness 0.1524)
				)
				(justify mirror)
			)
		)
		(property "Device Type" "R402H16"
			(at -0.064008 -5.517896 270)
			(unlocked yes)
			(layer "B.Fab")
			(hide yes)
			(effects
				(font
					(size 1.016 1.016)
					(thickness 0.1524)
				)
				(justify mirror)
			)
		)
		(duplicate_pad_numbers_are_jumpers no)
		(fp_line
			(start -0.508 -0.9398)
			(end 0.508 -0.9398)
			(stroke
				(width 0.1524)
				(type default)
			)
			(layer "B.SilkS")
		)
		(fp_line
			(start 0.508 -0.9398)
			(end 0.508 0.9398)
			(stroke
				(width 0.1524)
				(type default)
			)
			(layer "B.SilkS")
		)
		(fp_rect
			(start 0.508 0.9398)
			(end -0.508 -0.9398)
			(stroke
				(width 0)
				(type default)
			)
			(fill no)
			(layer "B.CrtYd")
		)
		(fp_rect
			(start 0.508 0.9398)
			(end -0.508 -0.9398)
			(stroke
				(width 0)
				(type default)
			)
			(fill no)
			(layer "B.Fab")
		)
		(pad "1" smd custom
			(at 0 -0.4445 90)
			(size 0.1397 0.1397)
			(layers "B.Cu" "B.Mask" "B.Paste")
			(net "P1V8_C")
			(options
				(clearance outline)
				(anchor circle)
			)
			(primitives
				(gr_poly
					(pts
						(arc
							(start -0.1778 0.2794)
							(mid -0.249642 0.249642)
							(end -0.2794 0.1778)
						)
						(arc
							(start -0.2794 -0.1778)
							(mid -0.249642 -0.249642)
							(end -0.1778 -0.2794)
						)
						(arc
							(start 0.1778 -0.2794)
							(mid 0.249642 -0.249642)
							(end 0.2794 -0.1778)
						)
						(arc
							(start 0.2794 0.1778)
							(mid 0.249642 0.249642)
							(end 0.1778 0.2794)
						)
					)
					(width 0)
					(fill yes)
				)
			)
		)
		(pad "2" smd custom
			(at 0 0.4445 90)
			(size 0.1397 0.1397)
			(layers "B.Cu" "B.Mask" "B.Paste")
			(net "IOC_UART_1_RX")
			(options
				(clearance outline)
				(anchor circle)
			)
			(primitives
				(gr_poly
					(pts
						(arc
							(start -0.1778 0.2794)
							(mid -0.249642 0.249642)
							(end -0.2794 0.1778)
						)
						(arc
							(start -0.2794 -0.1778)
							(mid -0.249642 -0.249642)
							(end -0.1778 -0.2794)
						)
						(arc
							(start 0.1778 -0.2794)
							(mid 0.249642 -0.249642)
							(end 0.2794 -0.1778)
						)
						(arc
							(start 0.2794 0.1778)
							(mid 0.249642 0.249642)
							(end 0.1778 0.2794)
						)
					)
					(width 0)
					(fill yes)
				)
			)
		)
	)
	(footprint ""
		(layer "B.Cu")
		(at 109.9566 -87.0204)
		(property "Reference" "R104"
			(at 0 0 0)
			(layer "B.SilkS")
			(hide yes)
			(effects
				(font
					(size 1.27 1.27)
				)
				(justify mirror)
			)
		)
		(property "Value" "4K75R2F-1-GP"
			(at -0.064008 -3.993896 0)
			(unlocked yes)
			(layer "B.Fab")
			(hide yes)
			(effects
				(font
					(size 1.016 1.016)
					(thickness 0.1524)
				)
				(justify mirror)
			)
		)
		(property "Device Type" "R402H16"
			(at -0.064008 -5.517896 0)
			(unlocked yes)
			(layer "B.Fab")
			(hide yes)
			(effects
				(font
					(size 1.016 1.016)
					(thickness 0.1524)
				)
				(justify mirror)
			)
		)
		(duplicate_pad_numbers_are_jumpers no)
		(fp_line
			(start -0.508 -0.9398)
			(end 0.508 -0.9398)
			(stroke
				(width 0.1524)
				(type default)
			)
			(layer "B.SilkS")
		)
		(fp_line
			(start 0.508 -0.9398)
			(end 0.508 0.9398)
			(stroke
				(width 0.1524)
				(type default)
			)
			(layer "B.SilkS")
		)
		(fp_rect
			(start 0.508 0.9398)
			(end -0.508 -0.9398)
			(stroke
				(width 0)
				(type default)
			)
			(fill no)
			(layer "B.CrtYd")
		)
		(fp_rect
			(start 0.508 0.9398)
			(end -0.508 -0.9398)
			(stroke
				(width 0)
				(type default)
			)
			(fill no)
			(layer "B.Fab")
		)
		(pad "1" smd custom
			(at 0 -0.4445 180)
			(size 0.1397 0.1397)
			(layers "B.Cu" "B.Mask" "B.Paste")
			(net "TMUX_EN")
			(options
				(clearance outline)
				(anchor circle)
			)
			(primitives
				(gr_poly
					(pts
						(arc
							(start -0.1778 0.2794)
							(mid -0.249642 0.249642)
							(end -0.2794 0.1778)
						)
						(arc
							(start -0.2794 -0.1778)
							(mid -0.249642 -0.249642)
							(end -0.1778 -0.2794)
						)
						(arc
							(start 0.1778 -0.2794)
							(mid 0.249642 -0.249642)
							(end 0.2794 -0.1778)
						)
						(arc
							(start 0.2794 0.1778)
							(mid 0.249642 0.249642)
							(end 0.1778 0.2794)
						)
					)
					(width 0)
					(fill yes)
				)
			)
		)
		(pad "2" smd custom
			(at 0 0.4445 180)
			(size 0.1397 0.1397)
			(layers "B.Cu" "B.Mask" "B.Paste")
			(net "P1V8_E")
			(options
				(clearance outline)
				(anchor circle)
			)
			(primitives
				(gr_poly
					(pts
						(arc
							(start -0.1778 0.2794)
							(mid -0.249642 0.249642)
							(end -0.2794 0.1778)
						)
						(arc
							(start -0.2794 -0.1778)
							(mid -0.249642 -0.249642)
							(end -0.1778 -0.2794)
						)
						(arc
							(start 0.1778 -0.2794)
							(mid 0.249642 -0.249642)
							(end 0.2794 -0.1778)
						)
						(arc
							(start 0.2794 0.1778)
							(mid 0.249642 0.249642)
							(end 0.1778 0.2794)
						)
					)
					(width 0)
					(fill yes)
				)
			)
		)
	)
	(footprint ""
		(layer "B.Cu")
		(at 70.485 -48.133 90)
		(property "Reference" "L16"
			(at 0 0 90)
			(layer "B.SilkS")
			(hide yes)
			(effects
				(font
					(size 1.27 1.27)
				)
				(justify mirror)
			)
		)
		(property "Value" "MPZ2012S300AT-GP"
			(at 0 -4.2418 90)
			(unlocked yes)
			(layer "B.Fab")
			(hide yes)
			(effects
				(font
					(size 1.016 1.016)
					(thickness 0.1524)
				)
				(justify mirror)
			)
		)
		(property "Device Type" "L805H42"
			(at 0 -5.7912 90)
			(unlocked yes)
			(layer "B.Fab")
			(hide yes)
			(effects
				(font
					(size 1.016 1.016)
					(thickness 0.1524)
				)
				(justify mirror)
			)
		)
		(duplicate_pad_numbers_are_jumpers no)
		(fp_line
			(start 0.889 -1.7018)
			(end -0.889 -1.7018)
			(stroke
				(width 0.1524)
				(type default)
			)
			(layer "B.SilkS")
		)
		(fp_line
			(start -0.889 -1.7018)
			(end -0.889 1.7018)
			(stroke
				(width 0.1524)
				(type default)
			)
			(layer "B.SilkS")
		)
		(fp_line
			(start 0.889 1.7018)
			(end 0.889 -1.7018)
			(stroke
				(width 0.1524)
				(type default)
			)
			(layer "B.SilkS")
		)
		(fp_line
			(start -0.889 1.7018)
			(end 0.889 1.7018)
			(stroke
				(width 0.1524)
				(type default)
			)
			(layer "B.SilkS")
		)
		(fp_rect
			(start 0.9652 1.778)
			(end -0.9652 -1.778)
			(stroke
				(width 0)
				(type default)
			)
			(fill no)
			(layer "B.CrtYd")
		)
		(fp_rect
			(start 0.9652 1.778)
			(end -0.9652 -1.778)
			(stroke
				(width 0)
				(type default)
			)
			(fill no)
			(layer "B.Fab")
		)
		(pad "1" smd rect
			(at 0 -0.9652 270)
			(size 1.397 1.143)
			(layers "B.Cu" "B.Mask" "B.Paste")
			(net "P0V9")
		)
		(pad "2" smd rect
			(at 0 0.9652 270)
			(size 1.397 1.143)
			(layers "B.Cu" "B.Mask" "B.Paste")
			(net "GB_VDDA")
		)
	)
	(footprint ""
		(layer "B.Cu")
		(at 117.5004 -76.0222 180)
		(property "Reference" "C131"
			(at 0 0 0)
			(layer "B.SilkS")
			(hide yes)
			(effects
				(font
					(size 1.27 1.27)
				)
				(justify mirror)
			)
		)
		(property "Value" "SCD1U6D3V1KX-GP"
			(at 2.8321 -1.7399 180)
			(unlocked yes)
			(layer "B.Fab")
			(hide yes)
			(effects
				(font
					(size 1.016 1.016)
					(thickness 0.1524)
				)
				(justify mirror)
			)
		)
		(property "Device Type" "C0201H13"
			(at 2.8321 -3.2639 180)
			(unlocked yes)
			(layer "B.Fab")
			(hide yes)
			(effects
				(font
					(size 1.016 1.016)
					(thickness 0.1524)
				)
				(justify mirror)
			)
		)
		(duplicate_pad_numbers_are_jumpers no)
		(fp_rect
			(start 0.2794 0.6477)
			(end -0.2794 -0.6477)
			(stroke
				(width 0)
				(type default)
			)
			(fill no)
			(layer "B.CrtYd")
		)
		(fp_rect
			(start 0.2794 0.6477)
			(end -0.2794 -0.6477)
			(stroke
				(width 0)
				(type default)
			)
			(fill no)
			(layer "B.Fab")
		)
		(pad "1" smd custom
			(at 0 -0.2794)
			(size 0.0762 0.0762)
			(layers "B.Cu" "B.Mask" "B.Paste")
			(net "P1V8_E")
			(options
				(clearance outline)
				(anchor circle)
			)
			(primitives
				(gr_poly
					(pts
						(arc
							(start 0.1524 0.127)
							(mid 0.137521 0.162921)
							(end 0.1016 0.1778)
						)
						(arc
							(start -0.1016 0.1778)
							(mid -0.137521 0.162921)
							(end -0.1524 0.127)
						)
						(arc
							(start -0.1524 -0.127)
							(mid -0.137521 -0.162921)
							(end -0.1016 -0.1778)
						)
						(arc
							(start 0.1016 -0.1778)
							(mid 0.137521 -0.162921)
							(end 0.1524 -0.127)
						)
					)
					(width 0)
					(fill yes)
				)
			)
		)
		(pad "2" smd custom
			(at 0 0.2794)
			(size 0.0762 0.0762)
			(layers "B.Cu" "B.Mask" "B.Paste")
			(net "GND")
			(options
				(clearance outline)
				(anchor circle)
			)
			(primitives
				(gr_poly
					(pts
						(arc
							(start 0.1524 0.127)
							(mid 0.137521 0.162921)
							(end 0.1016 0.1778)
						)
						(arc
							(start -0.1016 0.1778)
							(mid -0.137521 0.162921)
							(end -0.1524 0.127)
						)
						(arc
							(start -0.1524 -0.127)
							(mid -0.137521 -0.162921)
							(end -0.1016 -0.1778)
						)
						(arc
							(start 0.1016 -0.1778)
							(mid 0.137521 -0.162921)
							(end 0.1524 -0.127)
						)
					)
					(width 0)
					(fill yes)
				)
			)
		)
	)
	(footprint ""
		(layer "B.Cu")
		(at 116.84 -86.995 180)
		(property "Reference" "R143"
			(at 0 0 0)
			(layer "B.SilkS")
			(hide yes)
			(effects
				(font
					(size 1.27 1.27)
				)
				(justify mirror)
			)
		)
		(property "Value" "4K7R2F-GP"
			(at -0.064008 -3.993896 180)
			(unlocked yes)
			(layer "B.Fab")
			(hide yes)
			(effects
				(font
					(size 1.016 1.016)
					(thickness 0.1524)
				)
				(justify mirror)
			)
		)
		(property "Device Type" "R402H16"
			(at -0.064008 -5.517896 180)
			(unlocked yes)
			(layer "B.Fab")
			(hide yes)
			(effects
				(font
					(size 1.016 1.016)
					(thickness 0.1524)
				)
				(justify mirror)
			)
		)
		(duplicate_pad_numbers_are_jumpers no)
		(fp_line
			(start 0.508 -0.9398)
			(end 0.508 0.9398)
			(stroke
				(width 0.1524)
				(type default)
			)
			(layer "B.SilkS")
		)
		(fp_line
			(start -0.508 -0.9398)
			(end 0.508 -0.9398)
			(stroke
				(width 0.1524)
				(type default)
			)
			(layer "B.SilkS")
		)
		(fp_rect
			(start 0.508 0.9398)
			(end -0.508 -0.9398)
			(stroke
				(width 0)
				(type default)
			)
			(fill no)
			(layer "B.CrtYd")
		)
		(fp_rect
			(start 0.508 0.9398)
			(end -0.508 -0.9398)
			(stroke
				(width 0)
				(type default)
			)
			(fill no)
			(layer "B.Fab")
		)
		(pad "1" smd custom
			(at 0 -0.4445)
			(size 0.1397 0.1397)
			(layers "B.Cu" "B.Mask" "B.Paste")
			(net "EXP_XM_ADDR_17")
			(options
				(clearance outline)
				(anchor circle)
			)
			(primitives
				(gr_poly
					(pts
						(arc
							(start -0.1778 0.2794)
							(mid -0.249642 0.249642)
							(end -0.2794 0.1778)
						)
						(arc
							(start -0.2794 -0.1778)
							(mid -0.249642 -0.249642)
							(end -0.1778 -0.2794)
						)
						(arc
							(start 0.1778 -0.2794)
							(mid 0.249642 -0.249642)
							(end 0.2794 -0.1778)
						)
						(arc
							(start 0.2794 0.1778)
							(mid 0.249642 0.249642)
							(end 0.1778 0.2794)
						)
					)
					(width 0)
					(fill yes)
				)
			)
		)
		(pad "2" smd custom
			(at 0 0.4445)
			(size 0.1397 0.1397)
			(layers "B.Cu" "B.Mask" "B.Paste")
			(net "GND")
			(options
				(clearance outline)
				(anchor circle)
			)
			(primitives
				(gr_poly
					(pts
						(arc
							(start -0.1778 0.2794)
							(mid -0.249642 0.249642)
							(end -0.2794 0.1778)
						)
						(arc
							(start -0.2794 -0.1778)
							(mid -0.249642 -0.249642)
							(end -0.1778 -0.2794)
						)
						(arc
							(start 0.1778 -0.2794)
							(mid 0.249642 -0.249642)
							(end 0.2794 -0.1778)
						)
						(arc
							(start 0.2794 0.1778)
							(mid 0.249642 0.249642)
							(end 0.1778 0.2794)
						)
					)
					(width 0)
					(fill yes)
				)
			)
		)
	)
)
